# T6G (Grand Teton) — schematic netlist excerpt (pin names and nets, part order shuffled) for the footprints in the layout excerpt that follows; sources: Cadence DE-HDL packaged netlist, KiCad conversion of 04192023_DAF0TMB3IC0_F0TG_MB_C_brd_V02_OCP.brd

C209  Q_CAP  0.001UF 50V 10% EMPTY  pkg C0402  page 27 : A = JTAG_CPU0_TRST_N ; B = GND
C2549  Q_CAP  22UF 4V 20% X6S  pkg C0402  page 70 : A = PVDDCR_SOC_P0 ; B = GND
C324  Q_CAP  100UF 4V 20% X6S  pkg C0805  page 334 : A = P0V9_CPU1_RT1_2A ; B = GND

(kicad_pcb
	(version 20260206)
	(generator "pcbnew")
	(generator_version "10.0")
	(general
		(thickness 1.6)
		(legacy_teardrops no)
	)
	(paper "A4")
	(title_block
		(title "04192023_DAF0TMB3IC0_F0TG_MB_C_brd_V02_OCP.brd")
		(comment 1 "Grand Teton / footprints 4944-4946 of 8354")
	)
	(layers
		(0 "F.Cu" signal "TOP")
		(4 "In1.Cu" signal "GND")
		(6 "In2.Cu" signal "IN1")
		(8 "In3.Cu" signal "GND1")
		(10 "In4.Cu" signal "IN2")
		(12 "In5.Cu" signal "GND2")
		(14 "In6.Cu" signal "IN3")
		(16 "In7.Cu" signal "GND3")
		(18 "In8.Cu" signal "VCC")
		(20 "In9.Cu" signal "VCC1")
		(22 "In10.Cu" signal "GND4")
		(24 "In11.Cu" signal "IN4")
		(26 "In12.Cu" signal "GND5")
		(28 "In13.Cu" signal "IN5")
		(30 "In14.Cu" signal "GND6")
		(32 "In15.Cu" signal "IN6")
		(34 "In16.Cu" signal "GND7")
		(2 "B.Cu" signal "BOTTOM")
		(9 "F.Adhes" user "F.Adhesive")
		(11 "B.Adhes" user "B.Adhesive")
		(13 "F.Paste" user "Package Geometry/Pastemask Top")
		(15 "B.Paste" user "Package Geometry/Pastemask Bottom")
		(5 "F.SilkS" user "Ref Des/Silkscreen Top")
		(7 "B.SilkS" user "Ref Des/Silkscreen Bottom")
		(1 "F.Mask" user "Board Geometry/Soldermask Top")
		(3 "B.Mask" user "Board Geometry/Soldermask Bottom")
		(17 "Dwgs.User" user "User.Drawings")
		(19 "Cmts.User" user "User.Comments")
		(21 "Eco1.User" user "User.Eco1")
		(23 "Eco2.User" user "User.Eco2")
		(25 "Edge.Cuts" user "Board Geometry/Outline")
		(27 "Margin" user)
		(31 "F.CrtYd" user "Package Geometry/Place Bound Top")
		(29 "B.CrtYd" user "Package Geometry/Place Bound Bottom")
		(35 "F.Fab" user "Ref Des/Assembly Top")
		(33 "B.Fab" user "Ref Des/Assembly Bottom")
	)
	(footprint ""
		(layer "B.Cu")
		(at 74.940668 -388.846568)
		(property "Reference" "C324"
			(at 0 0 0)
			(layer "B.SilkS")
			(hide yes)
			(effects
				(font
					(size 1.27 1.27)
				)
				(justify mirror)
			)
		)
		(property "Value" ""
			(at 0 0 0)
			(layer "B.Fab")
			(effects
				(font
					(size 1.27 1.27)
				)
				(justify mirror)
			)
		)
		(duplicate_pad_numbers_are_jumpers no)
		(fp_line
			(start -1.524 -0.762)
			(end -1.524 0.762)
			(stroke
				(width 0.1524)
				(type default)
			)
			(layer "B.SilkS")
		)
		(fp_line
			(start -1.524 0.762)
			(end 1.524 0.762)
			(stroke
				(width 0.1524)
				(type default)
			)
			(layer "B.SilkS")
		)
		(fp_line
			(start 1.524 -0.762)
			(end -1.524 -0.762)
			(stroke
				(width 0.1524)
				(type default)
			)
			(layer "B.SilkS")
		)
		(fp_line
			(start 1.524 0.762)
			(end 1.524 -0.762)
			(stroke
				(width 0.1524)
				(type default)
			)
			(layer "B.SilkS")
		)
		(fp_line
			(start -1.1049 -0.724916)
			(end 1.1049 -0.724916)
			(stroke
				(width 0.1)
				(type default)
			)
			(layer "B.Fab")
		)
		(fp_line
			(start -1.1049 0.724916)
			(end -1.1049 -0.724916)
			(stroke
				(width 0.1)
				(type default)
			)
			(layer "B.Fab")
		)
		(fp_line
			(start 1.1049 -0.724916)
			(end 1.1049 0.724916)
			(stroke
				(width 0.1)
				(type default)
			)
			(layer "B.Fab")
		)
		(fp_line
			(start 1.1049 0.724916)
			(end -1.1049 0.724916)
			(stroke
				(width 0.1)
				(type default)
			)
			(layer "B.Fab")
		)
		(pad "1" smd rect
			(at 0.889 0)
			(size 1.016 1.27)
			(layers "B.Cu" "B.Mask" "B.Paste")
			(net "P0V9_CPU1_RT1_2A")
		)
		(pad "2" smd rect
			(at -0.889 0)
			(size 1.016 1.27)
			(layers "B.Cu" "B.Mask" "B.Paste")
			(net "GND")
		)
	)
	(footprint ""
		(layer "B.Cu")
		(at 356.057454 -253.43231)
		(property "Reference" "C2549"
			(at 0 0 0)
			(layer "B.SilkS")
			(hide yes)
			(effects
				(font
					(size 1.27 1.27)
				)
				(justify mirror)
			)
		)
		(property "Value" ""
			(at 0 0 0)
			(layer "B.Fab")
			(effects
				(font
					(size 1.27 1.27)
				)
				(justify mirror)
			)
		)
		(duplicate_pad_numbers_are_jumpers no)
		(fp_line
			(start -0.7874 -0.4064)
			(end -0.7874 0.4064)
			(stroke
				(width 0.1524)
				(type default)
			)
			(layer "B.SilkS")
		)
		(fp_line
			(start -0.7874 0.4064)
			(end 0.7874 0.4064)
			(stroke
				(width 0.1524)
				(type default)
			)
			(layer "B.SilkS")
		)
		(fp_line
			(start 0.7874 -0.4064)
			(end -0.7874 -0.4064)
			(stroke
				(width 0.1524)
				(type default)
			)
			(layer "B.SilkS")
		)
		(fp_line
			(start 0.7874 0.4064)
			(end 0.7874 -0.4064)
			(stroke
				(width 0.1524)
				(type default)
			)
			(layer "B.SilkS")
		)
		(fp_line
			(start -0.67945 -0.3048)
			(end -0.67945 0.3048)
			(stroke
				(width 0.1)
				(type default)
			)
			(layer "B.Fab")
		)
		(fp_line
			(start -0.67945 0.3048)
			(end -0.120396 0.3048)
			(stroke
				(width 0.1)
				(type default)
			)
			(layer "B.Fab")
		)
		(fp_line
			(start -0.12065 -0.3048)
			(end -0.67945 -0.3048)
			(stroke
				(width 0.1)
				(type default)
			)
			(layer "B.Fab")
		)
		(fp_line
			(start -0.12065 -0.2794)
			(end -0.12065 -0.3048)
			(stroke
				(width 0.1)
				(type default)
			)
			(layer "B.Fab")
		)
		(fp_line
			(start -0.120396 0.2794)
			(end 0.12065 0.2794)
			(stroke
				(width 0.1)
				(type default)
			)
			(layer "B.Fab")
		)
		(fp_line
			(start -0.120396 0.3048)
			(end -0.120396 0.2794)
			(stroke
				(width 0.1)
				(type default)
			)
			(layer "B.Fab")
		)
		(fp_line
			(start 0.12065 -0.305054)
			(end 0.12065 -0.2794)
			(stroke
				(width 0.1)
				(type default)
			)
			(layer "B.Fab")
		)
		(fp_line
			(start 0.12065 -0.2794)
			(end -0.12065 -0.2794)
			(stroke
				(width 0.1)
				(type default)
			)
			(layer "B.Fab")
		)
		(fp_line
			(start 0.12065 0.2794)
			(end 0.12065 0.3048)
			(stroke
				(width 0.1)
				(type default)
			)
			(layer "B.Fab")
		)
		(fp_line
			(start 0.12065 0.3048)
			(end 0.67945 0.3048)
			(stroke
				(width 0.1)
				(type default)
			)
			(layer "B.Fab")
		)
		(fp_line
			(start 0.67945 -0.305054)
			(end 0.12065 -0.305054)
			(stroke
				(width 0.1)
				(type default)
			)
			(layer "B.Fab")
		)
		(fp_line
			(start 0.67945 0.3048)
			(end 0.67945 -0.305054)
			(stroke
				(width 0.1)
				(type default)
			)
			(layer "B.Fab")
		)
		(pad "1" smd circle
			(at 0.40005 0 180)
			(size 0 0)
			(layers "B.Cu" "B.Mask" "B.Paste")
			(net "PVDDCR_SOC_P0")
		)
		(pad "2" smd circle
			(at -0.40005 0 180)
			(size 0 0)
			(layers "B.Cu" "B.Mask" "B.Paste")
			(net "GND")
		)
	)
	(footprint ""
		(layer "B.Cu")
		(at 375.456958 -208.530952 90)
		(property "Reference" "C209"
			(at 0 0 90)
			(layer "B.SilkS")
			(hide yes)
			(effects
				(font
					(size 1.27 1.27)
				)
				(justify mirror)
			)
		)
		(property "Value" ""
			(at 0 0 90)
			(layer "B.Fab")
			(effects
				(font
					(size 1.27 1.27)
				)
				(justify mirror)
			)
		)
		(duplicate_pad_numbers_are_jumpers no)
		(fp_line
			(start 0.7874 -0.4064)
			(end -0.7874 -0.4064)
			(stroke
				(width 0.1524)
				(type default)
			)
			(layer "B.SilkS")
		)
		(fp_line
			(start -0.7874 -0.4064)
			(end -0.7874 0.4064)
			(stroke
				(width 0.1524)
				(type default)
			)
			(layer "B.SilkS")
		)
		(fp_line
			(start 0.7874 0.4064)
			(end 0.7874 -0.4064)
			(stroke
				(width 0.1524)
				(type default)
			)
			(layer "B.SilkS")
		)
		(fp_line
			(start -0.7874 0.4064)
			(end 0.7874 0.4064)
			(stroke
				(width 0.1524)
				(type default)
			)
			(layer "B.SilkS")
		)
		(fp_line
			(start 0.67945 -0.305054)
			(end 0.12065 -0.305054)
			(stroke
				(width 0.1)
				(type default)
			)
			(layer "B.Fab")
		)
		(fp_line
			(start 0.12065 -0.305054)
			(end 0.12065 -0.2794)
			(stroke
				(width 0.1)
				(type default)
			)
			(layer "B.Fab")
		)
		(fp_line
			(start -0.12065 -0.3048)
			(end -0.67945 -0.3048)
			(stroke
				(width 0.1)
				(type default)
			)
			(layer "B.Fab")
		)
		(fp_line
			(start -0.67945 -0.3048)
			(end -0.67945 0.3048)
			(stroke
				(width 0.1)
				(type default)
			)
			(layer "B.Fab")
		)
		(fp_line
			(start 0.12065 -0.2794)
			(end -0.12065 -0.2794)
			(stroke
				(width 0.1)
				(type default)
			)
			(layer "B.Fab")
		)
		(fp_line
			(start -0.12065 -0.2794)
			(end -0.12065 -0.3048)
			(stroke
				(width 0.1)
				(type default)
			)
			(layer "B.Fab")
		)
		(fp_line
			(start 0.12065 0.2794)
			(end 0.12065 0.3048)
			(stroke
				(width 0.1)
				(type default)
			)
			(layer "B.Fab")
		)
		(fp_line
			(start -0.120396 0.2794)
			(end 0.12065 0.2794)
			(stroke
				(width 0.1)
				(type default)
			)
			(layer "B.Fab")
		)
		(fp_line
			(start 0.67945 0.3048)
			(end 0.67945 -0.305054)
			(stroke
				(width 0.1)
				(type default)
			)
			(layer "B.Fab")
		)
		(fp_line
			(start 0.12065 0.3048)
			(end 0.67945 0.3048)
			(stroke
				(width 0.1)
				(type default)
			)
			(layer "B.Fab")
		)
		(fp_line
			(start -0.120396 0.3048)
			(end -0.120396 0.2794)
			(stroke
				(width 0.1)
				(type default)
			)
			(layer "B.Fab")
		)
		(fp_line
			(start -0.67945 0.3048)
			(end -0.120396 0.3048)
			(stroke
				(width 0.1)
				(type default)
			)
			(layer "B.Fab")
		)
		(pad "1" smd circle
			(at 0.40005 0 270)
			(size 0 0)
			(layers "B.Cu" "B.Mask" "B.Paste")
			(net "JTAG_CPU0_TRST_N")
		)
		(pad "2" smd circle
			(at -0.40005 0 270)
			(size 0 0)
			(layers "B.Cu" "B.Mask" "B.Paste")
			(net "GND")
		)
	)
)
